FILE_TYPE = CONNECTIVITY;
{Allegro Design Entry HDL 17.2-2016 S081 (4005846) 1/11/2022}
"PAGE_NUMBER" = 29;
0"NC";
1"P5V_USB_REAR\g";
2"GND\g";
3"P3V3_AUX\g";
4"P5V_USB_REAR\g";
5"GND\g";
6"GND\g";
7"GND\g";
8"GND\g";
9"P3V3_AUX\g";
10"P5V_USB_REAR\g";
11"GND\g";
12"P3V3_AUX\g";
13"GND\g";
14"P3V3_AUX\g";
15"P3V3_AUX\g";
16"P3V3_AUX\g";
17"P3V3_AUX\g";
18"GND\g";
19"GND\g";
20"GND\g";
21"GND\g";
22"GND\g";
23"GND\g";
24"GND\g";
25"GND\g";
26"DEBUG_PORT_PRSNT";
27"USB3_01_FB_RXP";
28"DEBUG_PORT_PRSNT_R";
29"USB2_01_F_DN";
30"USB2_01_F_DP";
31"USB3_01_FB_RXN";
32"USB3_FPNL_TXP";
33"FM_DEBUG_PORT_R_PRSNT_N";
34"USB3_01_FB_TXN";
35"USB3_01_FB_TXP";
36"FM_DEBUG_PORT_PRSNT_N";
37"USB3_01_FB_RXP";
38"USB3_01_MUX_FB_RXN";
39"USB2_01_F_DN";
40"USB_FPNL_DP";
41"USB3_01_FB_TXP";
42"USB3_01_FB_TXN";
43"USB3_01_MUX_FB_TXN";
44"SPA_SIN_SW_DBG";
45"DEBUG_PORT_UART_RX";
46"DEBUG_PORT_PRSNT";
47"DEBUG_PORT_UART_TX";
48"SMB_DEBUG_AUX_LVC3_USB_R2_SCL";
49"SMB_DEBUG_AUX_LVC3_USB_R2_SDA";
50"DEBUG_PORT_UART_TX";
51"DEBUG_PORT_UART_RX";
52"SMB_DEBUG_AUX_LVC3_USB_SDA";
53"SMB_DEBUG_AUX_LVC3_USB_SCL";
54"USB3_MUX_PD";
55"DEBUG_PORT_PRSNT";
56"USB3_01_MUX_FB_RXN";
57"USB3_01_MUX_FB_RXP";
58"USB3_01_MUX_FB_TXN";
59"USB3_01_MUX_FB_TXP";
60"USB2_01_F_DP";
61"USB3_01_FB_RXN";
62"USB_FPNL_DN";
63"USB3_01_TXP_C";
64"USB3_01_MUX_FB_RXP";
65"SPA_SOUT_SW_DBG";
66"USB3_01_TXN_C";
67"USB3_FPNL_RXP";
68"USB3_FPNL_TXN";
69"USB3_FPNL_RXN";
70"DEBUG_PORT_PRSNT";
71"DEBUG_PORT_PRSNT";
72"USB3_01_MUX_FB_TXP";
%"UNIVERSAL_GND"
"1","(-1125,500)","0","logical_power","I100";
;
HDL_POWER"GND"
CDS_LIB"logical_power";
"A"25;
%"Q_RES"
"1","(-2250,1115)","0","pure_quanta","I101";
;
TOLERANCE"5%"
VALUE"0"
PART_NUMBER"CS00002JB13"
PACK_TYPE"0402LF"
WATTAGE"1/16W"
MATERIAL"CHIP"
CDS_LIB"pure_quanta"
LOCATION"R386"
$SEC"1"
CDS_SEC"1";
"B"
$PN"2"60;
"A"
$PN"1"40;
%"Q_INDUCTOR4P_12"
"1","(-2400,1675)","6","pure_quanta","I102";
;
VALUE"67/320MA"
MATERIAL"EMPTY"
PART_TYPE"SMLF"
PART_NUMBER"CX21SN67000"
CURRENT_AMP"320MA"
NEEDS_NO_SIZE"TRUE"
CDS_LMAN_SYM_OUTLINE"-250,175,250,-175"
CDS_LIB"pure_quanta"
LOCATION"L23"
$SEC"1"
CDS_SEC"1";
"1"
$PN"1"40;
"2"
$PN"2"60;
"3"
$PN"3"39;
"4"
$PN"4"62;
%"Q_RES"
"1","(-900,2925)","2","pure_quanta","I109";
;
WATTAGE"1/16W"
VALUE"0"
PACK_TYPE"0402LF"
TOLERANCE"5%"
MATERIAL"CHIP"
PART_NUMBER"CS00002JB13"
CDS_LIB"pure_quanta"
LOCATION"R675"
$SEC"1"
CDS_SEC"1";
"B"
$PN"2"37;
"A"
$PN"1"64;
%"Q_RES"
"1","(-800,2075)","2","pure_quanta","I111";
;
VALUE"0"
TOLERANCE"5%"
MATERIAL"CHIP"
PART_NUMBER"CS00002JB13"
PACK_TYPE"0402LF"
WATTAGE"1/16W"
CDS_LIB"pure_quanta"
LOCATION"R668"
$SEC"1"
CDS_SEC"1";
"B"
$PN"2"61;
"A"
$PN"1"38;
%"Q_INDUCTOR4P_12"
"1","(-875,2500)","2","pure_quanta","I113";
;
MATERIAL"EMPTY"
PART_TYPE"SMLF"
CURRENT_AMP"320MA"
PART_NUMBER"CX21SN67000"
VALUE"67/320MA"
NEEDS_NO_SIZE"TRUE"
CDS_LMAN_SYM_OUTLINE"-250,175,250,-175"
CDS_LIB"pure_quanta"
LOCATION"L22"
$SEC"1"
CDS_SEC"1";
"1"
$PN"1"64;
"2"
$PN"2"37;
"3"
$PN"3"61;
"4"
$PN"4"38;
%"Q_RES"
"1","(-775,4250)","2","pure_quanta","I122";
;
PACK_TYPE"0402LF"
MATERIAL"CHIP"
TOLERANCE"5%"
VALUE"0"
PART_NUMBER"CS00002JB13"
WATTAGE"1/16W"
CDS_LIB"pure_quanta"
LOCATION"R673"
$SEC"1"
CDS_SEC"1";
"B"
$PN"2"41;
"A"
$PN"1"72;
%"Q_INDUCTOR4P_12"
"1","(-850,3825)","2","pure_quanta","I123";
;
MATERIAL"EMPTY"
VALUE"67/320MA"
CURRENT_AMP"320MA"
PART_TYPE"SMLF"
PART_NUMBER"CX21SN67000"
CDS_LIB"pure_quanta"
CDS_LMAN_SYM_OUTLINE"-250,175,250,-175"
NEEDS_NO_SIZE"TRUE"
LOCATION"L21"
$SEC"1"
CDS_SEC"1";
"1"
$PN"1"72;
"2"
$PN"2"41;
"3"
$PN"3"42;
"4"
$PN"4"43;
%"Q_RES"
"1","(-775,3400)","2","pure_quanta","I124";
;
PART_NUMBER"CS00002JB13"
MATERIAL"CHIP"
WATTAGE"1/16W"
VALUE"0"
TOLERANCE"5%"
PACK_TYPE"0402LF"
CDS_LIB"pure_quanta"
LOCATION"R666"
$SEC"1"
CDS_SEC"1";
"B"
$PN"2"42;
"A"
$PN"1"43;
%"Q_RES"
"1","(350,-775)","2","pure_quanta","I135";
;
MATERIAL"CHIP"
TOLERANCE"5%"
WATTAGE"1/16W"
PACK_TYPE"0402LF"
VALUE"0"
PART_NUMBER"CS00002JB13"
CDS_LIB"pure_quanta"
LOCATION"R731"
$SEC"1"
CDS_SEC"1";
"B"
$PN"2"49;
"A"
$PN"1"52;
%"Q_RES"
"1","(350,-825)","2","pure_quanta","I136";
;
TOLERANCE"5%"
PACK_TYPE"0402LF"
MATERIAL"CHIP"
VALUE"0"
WATTAGE"1/16W"
PART_NUMBER"CS00002JB13"
CDS_LIB"pure_quanta"
LOCATION"R732"
$SEC"1"
CDS_SEC"1";
"B"
$PN"2"48;
"A"
$PN"1"53;
%"Q_RES"
"1","(-50,500)","0","pure_quanta","I141";
;
VALUE"0"
MATERIAL"CHIP"
PACK_TYPE"0402LF"
WATTAGE"1/16W"
TOLERANCE"5%"
PART_NUMBER"CS00002JB13"
CDS_LIB"pure_quanta"
LOCATION"R671"
$SEC"1"
CDS_SEC"1";
"B"
$PN"2"32;
"A"
$PN"1"63;
%"Q_CAP"
"2","(-50,225)","2","pure_quanta","I142";
;
PACK_TYPE"0402"
MATERIAL"EMPTY"
VALUE"0.1UF"
VOLTAGE"25V"
TOLERANCE"10%"
PART_NUMBER"CH4104K1B00"
CDS_LIB"pure_quanta"
LOCATION"C238"
$SEC"1"
CDS_SEC"1";
"A"
$PN"1"32;
"B"
$PN"2"63;
%"Q_CAP"
"2","(-50,50)","2","pure_quanta","I143";
;
PART_NUMBER"CH4104K1B00"
TOLERANCE"10%"
PACK_TYPE"0402"
VALUE"0.1UF"
VOLTAGE"25V"
MATERIAL"EMPTY"
CDS_LIB"pure_quanta"
LOCATION"C239"
$SEC"1"
CDS_SEC"1";
"A"
$PN"1"68;
"B"
$PN"2"66;
%"Q_RES"
"1","(-50,-125)","0","pure_quanta","I144";
;
PACK_TYPE"0402LF"
PART_NUMBER"CS00002JB13"
MATERIAL"CHIP"
TOLERANCE"5%"
VALUE"0"
WATTAGE"1/16W"
CDS_LIB"pure_quanta"
LOCATION"R672"
$SEC"1"
CDS_SEC"1";
"B"
$PN"2"68;
"A"
$PN"1"66;
%"VCCAUX15"
"1","(-2150,575)","0","logical_power","I145";
;
HDL_POWER"P3V3_AUX"
CDS_LIB"logical_power";
"A"12;
%"Q_CAP"
"1","(-2425,300)","2","pure_quanta","I146";
;
TOLERANCE"10%"
MATERIAL"X7R"
VOLTAGE"25V"
VALUE"0.1UF"
PART_NUMBER"CH4104K1B00"
PACK_TYPE"0402"
CDS_LIB"pure_quanta"
LOCATION"C237"
$SEC"1"
CDS_SEC"1";
"B"
$PN"2"22;
"A"
$PN"1"12;
%"UNIVERSAL_GND"
"1","(-2425,-75)","0","logical_power","I147";
;
HDL_POWER"GND"
CDS_LIB"logical_power";
"A"22;
%"Q_CAP"
"1","(-3050,275)","2","pure_quanta","I148";
;
MATERIAL"X7R"
VOLTAGE"25V"
PACK_TYPE"0402"
PART_NUMBER"CH4104K1B00"
TOLERANCE"10%"
VALUE"0.1UF"
CDS_LIB"pure_quanta"
LOCATION"C236"
$SEC"1"
CDS_SEC"1";
"B"
$PN"2"22;
"A"
$PN"1"12;
%"VCCAUX15"
"1","(-3800,-375)","0","logical_power","I149";
;
HDL_POWER"P3V3_AUX"
CDS_LIB"logical_power";
"A"9;
%"Q_CAP"
"1","(-3625,275)","2","pure_quanta","I150";
;
VALUE"0.1UF"
VOLTAGE"25V"
TOLERANCE"10%"
PART_NUMBER"CH4104K1B00"
MATERIAL"X7R"
PACK_TYPE"0402"
CDS_LIB"pure_quanta"
LOCATION"C219"
$SEC"1"
CDS_SEC"1";
"B"
$PN"2"22;
"A"
$PN"1"12;
%"UNIVERSAL_GND"
"1","(-1100,-1475)","0","logical_power","I151";
;
HDL_POWER"GND"
CDS_LIB"logical_power";
"A"13;
%"Q_RES"
"2","(-3800,-725)","0","pure_quanta","I153";
;
MATERIAL"EMPTY"
TOLERANCE"1%"
VALUE"10K"
WATTAGE"1/16W"
PART_NUMBER"CS31002FB08"
PACK_TYPE"0402LF"
CDS_LIB"pure_quanta"
LOCATION"R712"
$SEC"1"
CDS_SEC"1";
"A"
$PN"1"9;
"B"
$PN"2"54;
%"Q_RES"
"2","(-3600,-1275)","2","pure_quanta","I155";
;
WATTAGE"1/16W"
VALUE"100"
TOLERANCE"1%"
MATERIAL"CHIP"
PART_NUMBER"CS11002FB07"
PACK_TYPE"0402LF"
CDS_LIB"pure_quanta"
LOCATION"R694"
$SEC"1"
CDS_SEC"1";
"A"
$PN"1"54;
"B"
$PN"2"23;
%"UNIVERSAL_GND"
"1","(-3600,-1575)","0","logical_power","I156";
;
HDL_POWER"GND"
CDS_LIB"logical_power";
"A"23;
%"Q_RES"
"2","(4225,3800)","0","pure_quanta","I157";
;
PACK_TYPE"0402LF"
PART_NUMBER"CS41002FB09"
VALUE"100K"
TOLERANCE"1%"
MATERIAL"EMPTY"
WATTAGE"1/16W"
CDS_LIB"pure_quanta"
LOCATION"R274"
$SEC"1"
CDS_SEC"1";
"A"
$PN"1"15;
"B"
$PN"2"45;
%"VCCAUX15"
"1","(4225,4175)","0","logical_power","I159";
;
HDL_POWER"P3V3_AUX"
CDS_LIB"logical_power";
"A"15;
%"Q_CAP"
"1","(3475,3900)","0","pure_quanta","I161";
;
PACK_TYPE"0402"
VALUE"0.1UF"
TOLERANCE"10%"
MATERIAL"X7R"
VOLTAGE"25V"
PART_NUMBER"CH4104K1B00"
CDS_LIB"pure_quanta"
LOCATION"C149"
$SEC"1"
CDS_SEC"1";
"B"
$PN"2"6;
"A"
$PN"1"16;
%"VCCAUX15"
"1","(3225,4200)","2","logical_power","I162";
;
HDL_POWER"P3V3_AUX"
CDS_LIB"logical_power";
"A"16;
%"UNIVERSAL_GND"
"1","(3475,3650)","2","logical_power","I163";
;
HDL_POWER"GND"
CDS_LIB"logical_power";
"A"6;
%"74HC1G126GW"
"1","(2850,3475)","2","pure_quanta","I164";
;
MATERIAL"IC"
PART_TYPE"SMLF"
PART_NUMBER"AL1G0126007"
VALUE"74HC1G126GW"
CDS_LIB"pure_quanta"
NEEDS_NO_SIZE"TRUE"
CDS_LMAN_SYM_OUTLINE"-100,100,100,-100"
SEC_TYPE""
LOCATION"U36"
SEC"1";
"GND"
$PN"3"7;
"1"
$PN"1"70;
"5"
$PN"5"16;
"4"
$PN"4"44;
"2"
$PN"2"45;
%"VCCAUX15"
"1","(1275,4175)","0","logical_power","I165";
;
HDL_POWER"P3V3_AUX"
CDS_LIB"logical_power";
"A"17;
%"Q_RES"
"2","(1275,3800)","0","pure_quanta","I166";
;
VALUE"100K"
PACK_TYPE"0402LF"
MATERIAL"CHIP"
WATTAGE"1/16W"
TOLERANCE"1%"
PART_NUMBER"CS41002FB09"
CDS_LIB"pure_quanta"
LOCATION"R193"
$SEC"1"
CDS_SEC"1";
"A"
$PN"1"17;
"B"
$PN"2"44;
%"UNIVERSAL_GND"
"1","(3225,3275)","0","logical_power","I167";
;
HDL_POWER"GND"
CDS_LIB"logical_power";
"A"7;
%"Q_RES"
"2","(4100,1975)","2","pure_quanta","I170";
;
VALUE"100K"
PACK_TYPE"0402LF"
PART_NUMBER"CS41002FB09"
MATERIAL"EMPTY"
TOLERANCE"1%"
WATTAGE"1/16W"
CDS_LIB"pure_quanta"
LOCATION"R219"
$SEC"1"
CDS_SEC"1";
"A"
$PN"1"47;
"B"
$PN"2"18;
%"UNIVERSAL_GND"
"1","(4100,1625)","2","logical_power","I171";
;
HDL_POWER"GND"
CDS_LIB"logical_power";
"A"18;
%"Q_CAP"
"1","(2050,2675)","2","pure_quanta","I172";
;
VALUE"0.1UF"
TOLERANCE"10%"
MATERIAL"X7R"
VOLTAGE"25V"
PACK_TYPE"0402"
PART_NUMBER"CH4104K1B00"
CDS_LIB"pure_quanta"
LOCATION"C148"
$SEC"1"
CDS_SEC"1";
"B"
$PN"2"19;
"A"
$PN"1"14;
%"UNIVERSAL_GND"
"1","(2050,2425)","0","logical_power","I173";
;
HDL_POWER"GND"
CDS_LIB"logical_power";
"A"19;
%"74HC1G126GW"
"1","(2625,2275)","0","pure_quanta","I174";
;
PART_NUMBER"AL1G0126007"
MATERIAL"IC"
PART_TYPE"SMLF"
VALUE"74HC1G126GW"
SEC_TYPE""
CDS_LMAN_SYM_OUTLINE"-100,100,100,-100"
NEEDS_NO_SIZE"TRUE"
CDS_LIB"pure_quanta"
LOCATION"U29"
SEC"1";
"GND"
$PN"3"5;
"1"
$PN"1"46;
"5"
$PN"5"14;
"4"
$PN"4"47;
"2"
$PN"2"65;
%"UNIVERSAL_GND"
"1","(2300,1900)","2","logical_power","I175";
;
HDL_POWER"GND"
CDS_LIB"logical_power";
"A"5;
%"VCCAUX15"
"1","(2300,2975)","0","logical_power","I177";
;
HDL_POWER"P3V3_AUX"
CDS_LIB"logical_power";
"A"14;
%"UNIVERSAL_POWER"
"1","(3875,1150)","0","logical_power","I179";
;
HDL_POWER"P5V_USB_REAR"
CDS_LIB"logical_power";
"A"4;
%"UNIVERSAL_GND"
"1","(4875,150)","0","logical_power","I182";
;
HDL_POWER"GND"
CDS_LIB"logical_power";
"A"2;
%"UNIVERSAL_GND"
"1","(3875,75)","0","logical_power","I183";
;
HDL_POWER"GND"
CDS_LIB"logical_power";
"A"20;
%"Q_RES"
"2","(3775,125)","2","pure_quanta","I184";
;
TOLERANCE"1%"
VALUE"20K"
PACK_TYPE"0402LF"
MATERIAL"CHIP"
WATTAGE"1/16W"
PART_NUMBER"CS32002FB06"
SEC_TYPE"0402LF"
CDS_LIB"pure_quanta"
LOCATION"R205"
SEC"1";
"A"
$PN"1"28;
"B"
$PN"2"8;
%"UNIVERSAL_GND"
"1","(3775,-200)","2","logical_power","I185";
;
HDL_POWER"GND"
CDS_LIB"logical_power";
"A"8;
%"Q_CAP"
"1","(1750,1450)","0","pure_quanta","I193";
;
TOLERANCE"10%"
MATERIAL"X7R"
VALUE"470PF"
VOLTAGE"50V"
PACK_TYPE"0402"
PART_NUMBER"TMP_QCH14706KB18"
CDS_LIB"pure_quanta"
LOCATION"C179"
$SEC"1"
CDS_SEC"1";
"B"
$PN"2"11;
"A"
$PN"1"1;
%"Q_CAP"
"1","(1400,1450)","0","pure_quanta","I194";
;
PACK_TYPE"0402"
MATERIAL"X7R"
VALUE"470PF"
TOLERANCE"10%"
VOLTAGE"50V"
PART_NUMBER"TMP_QCH14706KB18"
CDS_LIB"pure_quanta"
LOCATION"C178"
$SEC"1"
CDS_SEC"1";
"B"
$PN"2"11;
"A"
$PN"1"1;
%"UNIVERSAL_GND"
"1","(1750,1075)","0","logical_power","I195";
;
HDL_POWER"GND"
CDS_LIB"logical_power";
"A"11;
%"UNIVERSAL_POWER"
"1","(825,1725)","0","logical_power","I197";
;
HDL_POWER"P5V_USB_REAR"
CDS_LIB"logical_power";
"A"1;
%"UNIVERSAL_GND"
"1","(2475,-1850)","0","logical_power","I200";
;
HDL_POWER"GND"
CDS_LIB"logical_power";
"A"21;
%"Q_RES"
"1","(3575,-450)","2","pure_quanta","I201";
;
TOLERANCE"5%"
WATTAGE"1/16W"
PACK_TYPE"0402LF"
PART_NUMBER"CS00002JB13"
MATERIAL"CHIP"
VALUE"0"
CDS_LIB"pure_quanta"
LOCATION"R707"
$SEC"1"
CDS_SEC"1";
"B"
$PN"2"36;
"A"
$PN"1"33;
%"2N7002A7"
"1","(3150,-1525)","2","pure_quanta","I202";
;
MATERIAL"IC"
PART_NUMBER"BAM70020068"
VALUE"2N7002A-7"
PART_TYPE"SMLF"
NEEDS_NO_SIZE"TRUE"
CDS_LMAN_SYM_OUTLINE"-300,325,300,-325"
CDS_LIB"pure_quanta"
LOCATION"Q6"
$SEC"1"
CDS_SEC"1";
"S"
$PN"S"21;
"D"
$PN"D"33;
"G"
$PN"G"71;
%"VCCAUX15"
"1","(4650,50)","2","logical_power","I203";
;
HDL_POWER"P3V3_AUX"
CDS_LIB"logical_power";
"A"3;
%"Q_RES"
"2","(4650,-175)","2","pure_quanta","I204";
;
MATERIAL"CHIP"
WATTAGE"1/16W"
TOLERANCE"1%"
VALUE"4.7K"
PART_NUMBER"CS24702FB06"
PACK_TYPE"0402LF"
CDS_LIB"pure_quanta"
LOCATION"R730"
$SEC"1"
CDS_SEC"1";
"A"
$PN"1"3;
"B"
$PN"2"33;
%"PI3PCIE3212ZBEX"
"1","(-1675,-825)","0","pure_quanta","I206";
;
MATERIAL"IC"
PART_NUMBER"AL003212003"
PART_TYPE"SMLF"
VALUE"PI3PCIE3212ZBEX"
CDS_LMAN_SYM_OUTLINE"-225,500,225,-500"
PIN_NAMES_ROTATE"True"
CDS_LIB"pure_quanta"
$LOCATION"U22"
CDS_LOCATION"U22"
$SEC"1"
CDS_SEC"1";
"PD"
$PN"2"54;
"GND0"
$PN"20"13;
"GND1"
$PN"5"13;
"GND2"
$PN"11"13;
"TH"
$PN"TH"0;
"C1_N"
$PN"12"48;
"C1_P"
$PN"13"49;
"C0_N"
$PN"14"50;
"C0_P"
$PN"15"51;
"B1_N"
$PN"16"69;
"B1_P"
$PN"17"67;
"B0_N"
$PN"18"66;
"B0_P"
$PN"19"63;
"SEL"
$PN"9"55;
"A1_N"
$PN"8"56;
"A1_P"
$PN"7"57;
"A0_N"
$PN"4"58;
"A0_P"
$PN"3"59;
"VDD0"
$PN"1"12;
"VDD1"
$PN"6"12;
"VDD2"
$PN"10"12;
%"DT1240E04LP7"
"1","(-2400,3050)","0","pure_quanta","I211";
;
VALUE"DT1240E-04LP-7"
PART_TYPE"SMLF"
MATERIAL"IC"
PART_NUMBER"BC001240Z01"
SEC_TYPE""
CDS_LIB"pure_quanta"
NEEDS_NO_SIZE"TRUE"
CDS_LMAN_SYM_OUTLINE"-250,400,250,-400"
LOCATION"U27"
SEC"1";
"NC2"
$PN"7"37;
"IO4"
$PN"5"61;
"IO2"
$PN"2"42;
"NC4"
$PN"10"41;
"NC3"
$PN"9"42;
"VSS2"
$PN"8"24;
"NC1"
$PN"6"61;
"IO3"
$PN"4"37;
"VSS1"
$PN"3"24;
"IO1"
$PN"1"41;
%"UNIVERSAL_GND"
"1","(-1925,3100)","2","logical_power","I212";
;
HDL_POWER"GND"
CDS_LIB"logical_power";
"A"24;
%"Q_CAP"
"1","(825,1450)","0","pure_quanta","I219";
;
VALUE"47UF"
VOLTAGE"6.3V"
PACK_TYPE"C1206"
TOLERANCE"20%"
PART_NUMBER"CH6471ME200"
MATERIAL"X6S"
CDS_LIB"pure_quanta"
LOCATION"C177"
$SEC"1"
CDS_SEC"1";
"B"
$PN"2"11;
"A"
$PN"1"1;
%"Q_CAP"
"1","(1150,1450)","0","pure_quanta","I220";
;
VOLTAGE"6.3V"
TOLERANCE"20%"
MATERIAL"X6S"
PACK_TYPE"C1206"
PART_NUMBER"CH6471ME200"
VALUE"47UF"
CDS_LIB"pure_quanta"
LOCATION"C327"
$SEC"1"
CDS_SEC"1";
"B"
$PN"2"11;
"A"
$PN"1"1;
%"CONN9_GSB3111315HR"
"1","(4375,525)","0","pure_quanta","I221";
;
PART_TYPE"THLF"
MATERIAL"IO"
VALUE"CONN9_GSB3111315HR"
PART_NUMBER"DFHS09FR401"
CDS_LIB"pure_quanta"
NEEDS_NO_SIZE"TRUE"
CDS_LMAN_SYM_OUTLINE"-275,300,275,-300"
LOCATION"J2"
$SEC"1"
CDS_SEC"1";
"SSRX-"
$PN"5"31;
"GND_D"
$PN"7"28;
"SSRX+"
$PN"6"27;
"D+"
$PN"3"30;
"D-"
$PN"2"29;
"SSTX-"
$PN"8"34;
"SSTX+"
$PN"9"35;
"G2"
$PN"G2"2;
"G1"
$PN"G1"2;
"GND"
$PN"4"20;
"VBUS"
$PN"1"4;
%"Q_RES"
"1","(2050,375)","0","pure_quanta","I222";
;
MATERIAL"CHIP"
VALUE"33.2"
TOLERANCE"1%"
PART_NUMBER"CS03322FB03"
PACK_TYPE"0402LF"
WATTAGE"1/16W"
CDS_LIB"pure_quanta"
LOCATION"R693"
$SEC"1"
CDS_SEC"1";
"B"
$PN"2"28;
"A"
$PN"1"26;
%"UNIVERSAL_POWER"
"1","(-275,1425)","0","logical_power","I95";
;
HDL_POWER"P5V_USB_REAR"
CDS_LIB"logical_power";
"A"10;
%"Q_RES"
"1","(-2450,2050)","0","pure_quanta","I96";
;
WATTAGE"1/16W"
VALUE"0"
PACK_TYPE"0402LF"
TOLERANCE"5%"
MATERIAL"CHIP"
PART_NUMBER"CS00002JB13"
CDS_LIB"pure_quanta"
LOCATION"R385"
$SEC"1"
CDS_SEC"1";
"B"
$PN"2"39;
"A"
$PN"1"62;
%"PRTR5V0U2X"
"1","(-725,1075)","0","pure_quanta","I99";
;
VALUE"PRTR5V0U2X"
PART_NUMBER"AL5V0U2X000"
MATERIAL"IC"
PART_TYPE"SMLF"
CDS_LIB"pure_quanta"
CDS_LMAN_SYM_OUTLINE"-175,125,175,-125"
NEEDS_NO_SIZE"TRUE"
LOCATION"U38"
$SEC"1"
CDS_SEC"1";
"IO2"
$PN"3"39;
"VCC"
$PN"4"10;
"GND"
$PN"1"25;
"IO1"
$PN"2"60;
END.
